# BASEBOARD_FAB2 (Tioga Pass) — schematic netlist excerpt (pin names and nets, part order shuffled) for the footprints in the layout excerpt that follows; sources: Cadence DE-HDL packaged netlist, KiCad conversion of Wiwynn_Tioga_Pass_MB.brd

R7D7  RES  1.00K 1% CHIP  pkg 0402  page 133 : A = P3V3_STBY ; B = IRQ_PIRQA_SPI_TPM_N
RT18  1R3F-GP  1%  pkg RCL_GP  page 207 : \1\ = VR_PVCCIN_CPU1_PHASE2_RC ; \2\ = GND
C1F12  CAP  0.22UF 16V 10% X7R  pkg 0402  page 181 : A = P3E_CPU1_PE3_MP_C_TXP<3> ; B = P3E_CPU1_PE3_MP_TXP<3>

(kicad_pcb
	(version 20260206)
	(generator "pcbnew")
	(generator_version "10.0")
	(general
		(thickness 1.6)
		(legacy_teardrops no)
	)
	(paper "A4")
	(title_block
		(title "Wiwynn_Tioga_Pass_MB.brd")
		(comment 1 "Tioga Pass / footprints 2069-2071 of 4770")
	)
	(layers
		(0 "F.Cu" signal "TOP")
		(4 "In1.Cu" signal "L2GND")
		(6 "In2.Cu" signal "L3")
		(8 "In3.Cu" signal "L4GND")
		(10 "In4.Cu" signal "L5")
		(12 "In5.Cu" signal "L6GND")
		(14 "In6.Cu" signal "L7VCC")
		(16 "In7.Cu" signal "L8VCC")
		(18 "In8.Cu" signal "L9GND")
		(20 "In9.Cu" signal "L10")
		(22 "In10.Cu" signal "L11GND")
		(24 "In11.Cu" signal "L12")
		(26 "In12.Cu" signal "L13GND")
		(2 "B.Cu" signal "BOTTOM")
		(9 "F.Adhes" user "F.Adhesive")
		(11 "B.Adhes" user "B.Adhesive")
		(13 "F.Paste" user "Package Geometry/Pastemask Top")
		(15 "B.Paste" user "Package Geometry/Pastemask Bottom")
		(5 "F.SilkS" user "Ref Des/Silkscreen Top")
		(7 "B.SilkS" user "Ref Des/Silkscreen Bottom")
		(1 "F.Mask" user "Board Geometry/Soldermask Top")
		(3 "B.Mask" user "Board Geometry/Soldermask Bottom")
		(17 "Dwgs.User" user "User.Drawings")
		(19 "Cmts.User" user "User.Comments")
		(21 "Eco1.User" user "User.Eco1")
		(23 "Eco2.User" user "User.Eco2")
		(25 "Edge.Cuts" user "Board Geometry/Outline")
		(27 "Margin" user)
		(31 "F.CrtYd" user "Package Geometry/Place Bound Top")
		(29 "B.CrtYd" user "Package Geometry/Place Bound Bottom")
		(35 "F.Fab" user "Ref Des/Assembly Top")
		(33 "B.Fab" user "Ref Des/Assembly Bottom")
	)
	(footprint ""
		(layer "F.Cu")
		(at 13.8938 -29.464 90)
		(property "Reference" "C1F12"
			(at 0 0 90)
			(layer "F.SilkS")
			(hide yes)
			(effects
				(font
					(size 1.27 1.27)
				)
			)
		)
		(property "Value" ""
			(at 0 0 90)
			(layer "F.Fab")
			(effects
				(font
					(size 1.27 1.27)
				)
			)
		)
		(duplicate_pad_numbers_are_jumpers no)
		(fp_rect
			(start -0.3048 -0.1016)
			(end 0.3048 0.9906)
			(stroke
				(width 0)
				(type default)
			)
			(fill no)
			(layer "F.CrtYd")
		)
		(fp_line
			(start 0.3048 -0.1016)
			(end -0.3048 -0.1016)
			(stroke
				(width 0.1)
				(type default)
			)
			(layer "F.Fab")
		)
		(fp_line
			(start -0.3048 -0.1016)
			(end -0.3048 0.9906)
			(stroke
				(width 0.1)
				(type default)
			)
			(layer "F.Fab")
		)
		(fp_line
			(start 0.3048 0.9906)
			(end 0.3048 -0.1016)
			(stroke
				(width 0.1)
				(type default)
			)
			(layer "F.Fab")
		)
		(fp_line
			(start -0.3048 0.9906)
			(end 0.3048 0.9906)
			(stroke
				(width 0.1)
				(type default)
			)
			(layer "F.Fab")
		)
		(pad "1" smd rect
			(at 0 0 90)
			(size 0.508 0.508)
			(layers "F.Cu" "F.Mask" "F.Paste")
			(net "P3E_CPU1_PE3_MP_C_TXP<3>")
		)
		(pad "2" smd rect
			(at 0 0.889 90)
			(size 0.508 0.508)
			(layers "F.Cu" "F.Mask" "F.Paste")
			(net "P3E_CPU1_PE3_MP_TXP<3>")
		)
		(zone
			(layer "F.Cu")
			(hatch none 0.5)
			(connect_pads
				(clearance 0)
			)
			(min_thickness 0.25)
			(keepout
				(tracks allowed)
				(vias not_allowed)
				(pads allowed)
				(copperpour not_allowed)
				(footprints allowed)
			)
			(placement
				(enabled no)
				(sheetname "")
			)
			(fill
				(thermal_gap 0.5)
				(thermal_bridge_width 0.5)
				(island_removal_mode 0)
			)
			(polygon
				(pts
					(xy 14.1478 -29.21) (xy 14.5288 -29.21) (xy 14.5288 -29.718) (xy 14.1478 -29.718)
				)
			)
		)
		(zone
			(layer "F.Cu")
			(hatch none 0.5)
			(connect_pads
				(clearance 0)
			)
			(min_thickness 0.25)
			(keepout
				(tracks not_allowed)
				(vias allowed)
				(pads allowed)
				(copperpour not_allowed)
				(footprints allowed)
			)
			(placement
				(enabled no)
				(sheetname "")
			)
			(fill
				(thermal_gap 0.5)
				(thermal_bridge_width 0.5)
				(island_removal_mode 0)
			)
			(polygon
				(pts
					(xy 14.1478 -29.21) (xy 14.5288 -29.21) (xy 14.5288 -29.718) (xy 14.1478 -29.718)
				)
			)
		)
	)
	(footprint ""
		(layer "F.Cu")
		(at 382.27 -87.3125 180)
		(property "Reference" "R7D7"
			(at 0 0 180)
			(layer "F.SilkS")
			(hide yes)
			(effects
				(font
					(size 1.27 1.27)
				)
			)
		)
		(property "Value" ""
			(at 0 0 180)
			(layer "F.Fab")
			(effects
				(font
					(size 1.27 1.27)
				)
			)
		)
		(duplicate_pad_numbers_are_jumpers no)
		(fp_poly
			(pts
				(xy -0.2794 -0.1016) (xy 0.2794 -0.1016) (xy 0.2794 0.9906) (xy -0.2794 0.9906)
			)
			(stroke
				(width 0)
				(type default)
			)
			(fill no)
			(layer "F.CrtYd")
		)
		(fp_line
			(start 0.2794 0.9906)
			(end 0.2794 -0.1016)
			(stroke
				(width 0.1)
				(type default)
			)
			(layer "F.Fab")
		)
		(fp_line
			(start 0.2794 -0.1016)
			(end -0.2794 -0.1016)
			(stroke
				(width 0.1)
				(type default)
			)
			(layer "F.Fab")
		)
		(fp_line
			(start -0.2794 0.9906)
			(end 0.2794 0.9906)
			(stroke
				(width 0.1)
				(type default)
			)
			(layer "F.Fab")
		)
		(fp_line
			(start -0.2794 -0.1016)
			(end -0.2794 0.9906)
			(stroke
				(width 0.1)
				(type default)
			)
			(layer "F.Fab")
		)
		(pad "1" smd rect
			(at 0 0 180)
			(size 0.508 0.508)
			(layers "F.Cu" "F.Mask" "F.Paste")
			(net "P3V3_STBY")
		)
		(pad "2" smd rect
			(at 0 0.889 180)
			(size 0.508 0.508)
			(layers "F.Cu" "F.Mask" "F.Paste")
			(net "IRQ_PIRQA_SPI_TPM_N")
		)
		(zone
			(layer "F.Cu")
			(hatch none 0.5)
			(connect_pads
				(clearance 0)
			)
			(min_thickness 0.25)
			(keepout
				(tracks not_allowed)
				(vias allowed)
				(pads allowed)
				(copperpour not_allowed)
				(footprints allowed)
			)
			(placement
				(enabled no)
				(sheetname "")
			)
			(fill
				(thermal_gap 0.5)
				(thermal_bridge_width 0.5)
				(island_removal_mode 0)
			)
			(polygon
				(pts
					(xy 382.524 -87.9475) (xy 382.016 -87.9475) (xy 382.016 -87.5665) (xy 382.524 -87.5665)
				)
			)
		)
		(zone
			(layer "F.Cu")
			(hatch none 0.5)
			(connect_pads
				(clearance 0)
			)
			(min_thickness 0.25)
			(keepout
				(tracks allowed)
				(vias not_allowed)
				(pads allowed)
				(copperpour not_allowed)
				(footprints allowed)
			)
			(placement
				(enabled no)
				(sheetname "")
			)
			(fill
				(thermal_gap 0.5)
				(thermal_bridge_width 0.5)
				(island_removal_mode 0)
			)
			(polygon
				(pts
					(xy 382.524 -87.5665) (xy 382.016 -87.5665) (xy 382.016 -87.9475) (xy 382.524 -87.9475)
				)
			)
		)
	)
	(footprint ""
		(layer "F.Cu")
		(at 35.7886 -61.214 -90)
		(property "Reference" "RT18"
			(at 0 0 270)
			(layer "F.SilkS")
			(hide yes)
			(effects
				(font
					(size 1.27 1.27)
				)
			)
		)
		(property "Value" "*"
			(at -0.0254 -2.6289 270)
			(unlocked yes)
			(layer "F.Fab")
			(hide yes)
			(effects
				(font
					(size 1.27 1.016)
					(thickness 0.1524)
				)
			)
		)
		(property "Device Type" "1R3F-GP_RCL_GP-1R3F-GP,64.1R00A"
			(at -0.0254 -4.1529 270)
			(unlocked yes)
			(layer "F.Fab")
			(hide yes)
			(effects
				(font
					(size 1.27 1.016)
					(thickness 0.1524)
				)
			)
		)
		(duplicate_pad_numbers_are_jumpers no)
		(fp_line
			(start -0.4826 0)
			(end -0.2032 0)
			(stroke
				(width 0.2032)
				(type default)
			)
			(layer "F.SilkS")
		)
		(fp_line
			(start 0.2032 0)
			(end 0.4826 0)
			(stroke
				(width 0.2032)
				(type default)
			)
			(layer "F.SilkS")
		)
		(fp_rect
			(start -0.5842 1.3335)
			(end 0.5842 -1.3335)
			(stroke
				(width 0)
				(type default)
			)
			(fill no)
			(layer "F.CrtYd")
		)
		(fp_rect
			(start -0.5842 1.3335)
			(end 0.5842 -1.3335)
			(stroke
				(width 0)
				(type default)
			)
			(fill no)
			(layer "F.Fab")
		)
		(pad "1" smd custom
			(at 0 -0.762 270)
			(size 0.2159 0.2159)
			(layers "F.Cu" "F.Mask" "F.Paste")
			(net "VR_PVCCIN_CPU1_PHASE2_RC")
			(options
				(clearance outline)
				(anchor circle)
			)
			(primitives
				(gr_poly
					(pts
						(arc
							(start -0.3302 -0.4318)
							(mid -0.402042 -0.402042)
							(end -0.4318 -0.3302)
						)
						(arc
							(start -0.4318 0.3302)
							(mid -0.402042 0.402042)
							(end -0.3302 0.4318)
						)
						(arc
							(start 0.3302 0.4318)
							(mid 0.402042 0.402042)
							(end 0.4318 0.3302)
						)
						(arc
							(start 0.4318 -0.3302)
							(mid 0.402042 -0.402042)
							(end 0.3302 -0.4318)
						)
					)
					(width 0)
					(fill yes)
				)
			)
		)
		(pad "2" smd custom
			(at 0 0.762 270)
			(size 0.2159 0.2159)
			(layers "F.Cu" "F.Mask" "F.Paste")
			(net "GND")
			(options
				(clearance outline)
				(anchor circle)
			)
			(primitives
				(gr_poly
					(pts
						(arc
							(start -0.3302 -0.4318)
							(mid -0.402042 -0.402042)
							(end -0.4318 -0.3302)
						)
						(arc
							(start -0.4318 0.3302)
							(mid -0.402042 0.402042)
							(end -0.3302 0.4318)
						)
						(arc
							(start 0.3302 0.4318)
							(mid 0.402042 0.402042)
							(end 0.4318 0.3302)
						)
						(arc
							(start 0.4318 -0.3302)
							(mid 0.402042 -0.402042)
							(end 0.3302 -0.4318)
						)
					)
					(width 0)
					(fill yes)
				)
			)
		)
	)
)
